# SCM (Grand Teton) — schematic netlist excerpt (pin names and nets, part order shuffled) for the footprints in the layout excerpt that follows; sources: Cadence DE-HDL packaged netlist, KiCad conversion of 12092022_DA0F0TMDCD0_F0T_Management_Board_D_brd_V3_OCP.brd

R488  Q_RES  4.7K 1% CHIP  pkg 0402LF  page 45 : A = P3V3_AUX ; B = SPI_PCH_IO2_FLASH_R1
C293  Q_CAP  10UF 25V 10% X6S  pkg C0805  page 54 : A = P3V3_AUX ; B = GND

(kicad_pcb
	(version 20260206)
	(generator "pcbnew")
	(generator_version "10.0")
	(general
		(thickness 1.6)
		(legacy_teardrops no)
	)
	(paper "A4")
	(title_block
		(title "12092022_DA0F0TMDCD0_F0T_Management_Board_D_brd_V3_OCP.brd")
		(comment 1 "Grand Teton / footprints 392-393 of 1440")
	)
	(layers
		(0 "F.Cu" signal "TOP")
		(4 "In1.Cu" signal "GND")
		(6 "In2.Cu" signal "IN1")
		(8 "In3.Cu" signal "GND1")
		(10 "In4.Cu" signal "IN2")
		(12 "In5.Cu" signal "VCC")
		(14 "In6.Cu" signal "VCC1")
		(16 "In7.Cu" signal "IN3")
		(18 "In8.Cu" signal "GND2")
		(20 "In9.Cu" signal "IN4")
		(22 "In10.Cu" signal "GND3")
		(2 "B.Cu" signal "BOTTOM")
		(9 "F.Adhes" user "F.Adhesive")
		(11 "B.Adhes" user "B.Adhesive")
		(13 "F.Paste" user "Package Geometry/Pastemask Top")
		(15 "B.Paste" user "Package Geometry/Pastemask Bottom")
		(5 "F.SilkS" user "Ref Des/Silkscreen Top")
		(7 "B.SilkS" user "Ref Des/Silkscreen Bottom")
		(1 "F.Mask" user "Board Geometry/Soldermask Top")
		(3 "B.Mask" user "Board Geometry/Soldermask Bottom")
		(17 "Dwgs.User" user "User.Drawings")
		(19 "Cmts.User" user "User.Comments")
		(21 "Eco1.User" user "User.Eco1")
		(23 "Eco2.User" user "User.Eco2")
		(25 "Edge.Cuts" user "Board Geometry/Outline")
		(27 "Margin" user)
		(31 "F.CrtYd" user "Package Geometry/Place Bound Top")
		(29 "B.CrtYd" user "Package Geometry/Place Bound Bottom")
		(35 "F.Fab" user "Ref Des/Assembly Top")
		(33 "B.Fab" user "Ref Des/Assembly Bottom")
	)
	(footprint ""
		(layer "F.Cu")
		(at 43.504104 -107.999784 -90)
		(property "Reference" "R488"
			(at 0 0 270)
			(layer "F.SilkS")
			(hide yes)
			(effects
				(font
					(size 1.27 1.27)
				)
			)
		)
		(property "Value" ""
			(at 0 0 270)
			(layer "F.Fab")
			(effects
				(font
					(size 1.27 1.27)
				)
			)
		)
		(duplicate_pad_numbers_are_jumpers no)
		(fp_line
			(start -0.7874 0.4064)
			(end -0.7874 -0.4064)
			(stroke
				(width 0.1524)
				(type default)
			)
			(layer "F.SilkS")
		)
		(fp_line
			(start 0.7874 0.4064)
			(end -0.7874 0.4064)
			(stroke
				(width 0.1524)
				(type default)
			)
			(layer "F.SilkS")
		)
		(fp_line
			(start -0.7874 -0.4064)
			(end 0.7874 -0.4064)
			(stroke
				(width 0.1524)
				(type default)
			)
			(layer "F.SilkS")
		)
		(fp_line
			(start 0.7874 -0.4064)
			(end 0.7874 0.4064)
			(stroke
				(width 0.1524)
				(type default)
			)
			(layer "F.SilkS")
		)
		(fp_line
			(start -0.67945 0.3048)
			(end -0.67945 -0.305054)
			(stroke
				(width 0.1)
				(type default)
			)
			(layer "F.Fab")
		)
		(fp_line
			(start -0.12065 0.3048)
			(end -0.67945 0.3048)
			(stroke
				(width 0.1)
				(type default)
			)
			(layer "F.Fab")
		)
		(fp_line
			(start 0.120396 0.3048)
			(end 0.120396 0.2794)
			(stroke
				(width 0.1)
				(type default)
			)
			(layer "F.Fab")
		)
		(fp_line
			(start 0.67945 0.3048)
			(end 0.120396 0.3048)
			(stroke
				(width 0.1)
				(type default)
			)
			(layer "F.Fab")
		)
		(fp_line
			(start -0.12065 0.2794)
			(end -0.12065 0.3048)
			(stroke
				(width 0.1)
				(type default)
			)
			(layer "F.Fab")
		)
		(fp_line
			(start 0.120396 0.2794)
			(end -0.12065 0.2794)
			(stroke
				(width 0.1)
				(type default)
			)
			(layer "F.Fab")
		)
		(fp_line
			(start -0.12065 -0.2794)
			(end 0.12065 -0.2794)
			(stroke
				(width 0.1)
				(type default)
			)
			(layer "F.Fab")
		)
		(fp_line
			(start 0.12065 -0.2794)
			(end 0.12065 -0.3048)
			(stroke
				(width 0.1)
				(type default)
			)
			(layer "F.Fab")
		)
		(fp_line
			(start 0.12065 -0.3048)
			(end 0.67945 -0.3048)
			(stroke
				(width 0.1)
				(type default)
			)
			(layer "F.Fab")
		)
		(fp_line
			(start 0.67945 -0.3048)
			(end 0.67945 0.3048)
			(stroke
				(width 0.1)
				(type default)
			)
			(layer "F.Fab")
		)
		(fp_line
			(start -0.67945 -0.305054)
			(end -0.12065 -0.305054)
			(stroke
				(width 0.1)
				(type default)
			)
			(layer "F.Fab")
		)
		(fp_line
			(start -0.12065 -0.305054)
			(end -0.12065 -0.2794)
			(stroke
				(width 0.1)
				(type default)
			)
			(layer "F.Fab")
		)
		(pad "1" smd circle
			(at -0.40005 0 270)
			(size 0 0)
			(layers "F.Cu" "F.Mask" "F.Paste")
			(net "P3V3_AUX")
		)
		(pad "2" smd circle
			(at 0.40005 0 270)
			(size 0 0)
			(layers "F.Cu" "F.Mask" "F.Paste")
			(net "SPI_PCH_IO2_FLASH_R1")
		)
	)
	(footprint ""
		(layer "F.Cu")
		(at 33.274 -54.356 -90)
		(property "Reference" "C293"
			(at 0 0 270)
			(layer "F.SilkS")
			(hide yes)
			(effects
				(font
					(size 1.27 1.27)
				)
			)
		)
		(property "Value" ""
			(at 0 0 270)
			(layer "F.Fab")
			(effects
				(font
					(size 1.27 1.27)
				)
			)
		)
		(duplicate_pad_numbers_are_jumpers no)
		(fp_line
			(start -1.651 0.8382)
			(end -1.651 -0.8382)
			(stroke
				(width 0.1524)
				(type default)
			)
			(layer "F.SilkS")
		)
		(fp_line
			(start 0 0.8382)
			(end 0 -0.8382)
			(stroke
				(width 0.1524)
				(type default)
			)
			(layer "F.SilkS")
		)
		(fp_line
			(start 1.651 0.8382)
			(end -1.651 0.8382)
			(stroke
				(width 0.1524)
				(type default)
			)
			(layer "F.SilkS")
		)
		(fp_line
			(start -1.651 -0.8382)
			(end 1.651 -0.8382)
			(stroke
				(width 0.1524)
				(type default)
			)
			(layer "F.SilkS")
		)
		(fp_line
			(start 1.651 -0.8382)
			(end 1.651 0.8382)
			(stroke
				(width 0.1524)
				(type default)
			)
			(layer "F.SilkS")
		)
		(fp_line
			(start -1.55956 0.7366)
			(end -1.524 0.7366)
			(stroke
				(width 0.1)
				(type default)
			)
			(layer "F.Fab")
		)
		(fp_line
			(start -1.524 0.7366)
			(end 1.524 0.7366)
			(stroke
				(width 0.1)
				(type default)
			)
			(layer "F.Fab")
		)
		(fp_line
			(start 1.524 0.7366)
			(end 1.55956 0.7366)
			(stroke
				(width 0.1)
				(type default)
			)
			(layer "F.Fab")
		)
		(fp_line
			(start 1.55956 0.7366)
			(end 1.55956 -0.7366)
			(stroke
				(width 0.1)
				(type default)
			)
			(layer "F.Fab")
		)
		(fp_line
			(start -1.55956 -0.7366)
			(end -1.55956 0.7366)
			(stroke
				(width 0.1)
				(type default)
			)
			(layer "F.Fab")
		)
		(fp_line
			(start -1.524 -0.7366)
			(end -1.55956 -0.7366)
			(stroke
				(width 0.1)
				(type default)
			)
			(layer "F.Fab")
		)
		(fp_line
			(start 1.524 -0.7366)
			(end -1.524 -0.7366)
			(stroke
				(width 0.1)
				(type default)
			)
			(layer "F.Fab")
		)
		(fp_line
			(start 1.55956 -0.7366)
			(end 1.524 -0.7366)
			(stroke
				(width 0.1)
				(type default)
			)
			(layer "F.Fab")
		)
		(pad "1" smd rect
			(at -0.94996 0 90)
			(size 1.1176 1.3716)
			(layers "F.Cu" "F.Mask" "F.Paste")
			(net "P3V3_AUX")
		)
		(pad "2" smd rect
			(at 0.94996 0 90)
			(size 1.1176 1.3716)
			(layers "F.Cu" "F.Mask" "F.Paste")
			(net "GND")
		)
	)
)
